# S9S_MB_2U (Grand Teton) — schematic netlist excerpt (pin names and nets, part order shuffled) for the footprints in the layout excerpt that follows; sources: Cadence DE-HDL packaged netlist, KiCad conversion of 03242023_DA0F0TMBIJ0_F0T_Motherboard_J_brd_V01_OCP.brd

R3589  Q_RES  33.2 1% CHIP  pkg 0402LF  page 232 : A = SMB_INA230_3V3AUX_SDA ; B = SMB_INA230_2_3V3AUX_SDA_R
R4478  Q_RES  33.2 1% CHIP  pkg 0402LF  page 211 : A = FM_9ZXL045_1_OE_N ; B = CLK_GPU_1_OE_N

(kicad_pcb
	(version 20260206)
	(generator "pcbnew")
	(generator_version "10.0")
	(general
		(thickness 1.6)
		(legacy_teardrops no)
	)
	(paper "A4")
	(title_block
		(title "03242023_DA0F0TMBIJ0_F0T_Motherboard_J_brd_V01_OCP.brd")
		(comment 1 "Grand Teton / footprints 1216-1217 of 6105")
	)
	(layers
		(0 "F.Cu" signal "TOP")
		(4 "In1.Cu" signal "GND")
		(6 "In2.Cu" signal "IN1")
		(8 "In3.Cu" signal "GND1")
		(10 "In4.Cu" signal "IN2")
		(12 "In5.Cu" signal "GND2")
		(14 "In6.Cu" signal "IN3")
		(16 "In7.Cu" signal "GND3")
		(18 "In8.Cu" signal "VCC")
		(20 "In9.Cu" signal "VCC1")
		(22 "In10.Cu" signal "GND4")
		(24 "In11.Cu" signal "IN4")
		(26 "In12.Cu" signal "GND5")
		(28 "In13.Cu" signal "IN5")
		(30 "In14.Cu" signal "GND6")
		(32 "In15.Cu" signal "IN6")
		(34 "In16.Cu" signal "GND7")
		(2 "B.Cu" signal "BOTTOM")
		(9 "F.Adhes" user "F.Adhesive")
		(11 "B.Adhes" user "B.Adhesive")
		(13 "F.Paste" user "Package Geometry/Pastemask Top")
		(15 "B.Paste" user "Package Geometry/Pastemask Bottom")
		(5 "F.SilkS" user "Ref Des/Silkscreen Top")
		(7 "B.SilkS" user "Ref Des/Silkscreen Bottom")
		(1 "F.Mask" user "Board Geometry/Soldermask Top")
		(3 "B.Mask" user "Board Geometry/Soldermask Bottom")
		(17 "Dwgs.User" user "User.Drawings")
		(19 "Cmts.User" user "User.Comments")
		(21 "Eco1.User" user "User.Eco1")
		(23 "Eco2.User" user "User.Eco2")
		(25 "Edge.Cuts" user "Board Geometry/Outline")
		(27 "Margin" user)
		(31 "F.CrtYd" user "Package Geometry/Place Bound Top")
		(29 "B.CrtYd" user "Package Geometry/Place Bound Bottom")
		(35 "F.Fab" user "Ref Des/Assembly Top")
		(33 "B.Fab" user "Ref Des/Assembly Bottom")
	)
	(footprint ""
		(layer "F.Cu")
		(at 213.41588 -47.335948 90)
		(property "Reference" "R3589"
			(at 0 0 90)
			(layer "F.SilkS")
			(hide yes)
			(effects
				(font
					(size 1.27 1.27)
				)
			)
		)
		(property "Value" ""
			(at 0 0 90)
			(layer "F.Fab")
			(effects
				(font
					(size 1.27 1.27)
				)
			)
		)
		(duplicate_pad_numbers_are_jumpers no)
		(fp_line
			(start 0.7874 -0.4064)
			(end 0.7874 0.4064)
			(stroke
				(width 0.1524)
				(type default)
			)
			(layer "F.SilkS")
		)
		(fp_line
			(start -0.7874 -0.4064)
			(end 0.7874 -0.4064)
			(stroke
				(width 0.1524)
				(type default)
			)
			(layer "F.SilkS")
		)
		(fp_line
			(start 0.7874 0.4064)
			(end -0.7874 0.4064)
			(stroke
				(width 0.1524)
				(type default)
			)
			(layer "F.SilkS")
		)
		(fp_line
			(start -0.7874 0.4064)
			(end -0.7874 -0.4064)
			(stroke
				(width 0.1524)
				(type default)
			)
			(layer "F.SilkS")
		)
		(fp_line
			(start -0.12065 -0.305054)
			(end -0.12065 -0.2794)
			(stroke
				(width 0.1)
				(type default)
			)
			(layer "F.Fab")
		)
		(fp_line
			(start -0.67945 -0.305054)
			(end -0.12065 -0.305054)
			(stroke
				(width 0.1)
				(type default)
			)
			(layer "F.Fab")
		)
		(fp_line
			(start 0.67945 -0.3048)
			(end 0.67945 0.3048)
			(stroke
				(width 0.1)
				(type default)
			)
			(layer "F.Fab")
		)
		(fp_line
			(start 0.12065 -0.3048)
			(end 0.67945 -0.3048)
			(stroke
				(width 0.1)
				(type default)
			)
			(layer "F.Fab")
		)
		(fp_line
			(start 0.12065 -0.2794)
			(end 0.12065 -0.3048)
			(stroke
				(width 0.1)
				(type default)
			)
			(layer "F.Fab")
		)
		(fp_line
			(start -0.12065 -0.2794)
			(end 0.12065 -0.2794)
			(stroke
				(width 0.1)
				(type default)
			)
			(layer "F.Fab")
		)
		(fp_line
			(start 0.120396 0.2794)
			(end -0.12065 0.2794)
			(stroke
				(width 0.1)
				(type default)
			)
			(layer "F.Fab")
		)
		(fp_line
			(start -0.12065 0.2794)
			(end -0.12065 0.3048)
			(stroke
				(width 0.1)
				(type default)
			)
			(layer "F.Fab")
		)
		(fp_line
			(start 0.67945 0.3048)
			(end 0.120396 0.3048)
			(stroke
				(width 0.1)
				(type default)
			)
			(layer "F.Fab")
		)
		(fp_line
			(start 0.120396 0.3048)
			(end 0.120396 0.2794)
			(stroke
				(width 0.1)
				(type default)
			)
			(layer "F.Fab")
		)
		(fp_line
			(start -0.12065 0.3048)
			(end -0.67945 0.3048)
			(stroke
				(width 0.1)
				(type default)
			)
			(layer "F.Fab")
		)
		(fp_line
			(start -0.67945 0.3048)
			(end -0.67945 -0.305054)
			(stroke
				(width 0.1)
				(type default)
			)
			(layer "F.Fab")
		)
		(pad "1" smd circle
			(at -0.40005 0 90)
			(size 0 0)
			(layers "F.Cu" "F.Mask" "F.Paste")
			(net "SMB_INA230_3V3AUX_SDA")
		)
		(pad "2" smd circle
			(at 0.40005 0 90)
			(size 0 0)
			(layers "F.Cu" "F.Mask" "F.Paste")
			(net "SMB_INA230_2_3V3AUX_SDA_R")
		)
	)
	(footprint ""
		(layer "F.Cu")
		(at 106.86034 -417.362386 180)
		(property "Reference" "R4478"
			(at 0 0 180)
			(layer "F.SilkS")
			(hide yes)
			(effects
				(font
					(size 1.27 1.27)
				)
			)
		)
		(property "Value" ""
			(at 0 0 180)
			(layer "F.Fab")
			(effects
				(font
					(size 1.27 1.27)
				)
			)
		)
		(duplicate_pad_numbers_are_jumpers no)
		(fp_line
			(start 0.7874 0.4064)
			(end -0.7874 0.4064)
			(stroke
				(width 0.1524)
				(type default)
			)
			(layer "F.SilkS")
		)
		(fp_line
			(start 0.7874 -0.4064)
			(end 0.7874 0.4064)
			(stroke
				(width 0.1524)
				(type default)
			)
			(layer "F.SilkS")
		)
		(fp_line
			(start -0.7874 0.4064)
			(end -0.7874 -0.4064)
			(stroke
				(width 0.1524)
				(type default)
			)
			(layer "F.SilkS")
		)
		(fp_line
			(start -0.7874 -0.4064)
			(end 0.7874 -0.4064)
			(stroke
				(width 0.1524)
				(type default)
			)
			(layer "F.SilkS")
		)
		(fp_line
			(start 0.67945 0.3048)
			(end 0.120396 0.3048)
			(stroke
				(width 0.1)
				(type default)
			)
			(layer "F.Fab")
		)
		(fp_line
			(start 0.67945 -0.3048)
			(end 0.67945 0.3048)
			(stroke
				(width 0.1)
				(type default)
			)
			(layer "F.Fab")
		)
		(fp_line
			(start 0.12065 -0.2794)
			(end 0.12065 -0.3048)
			(stroke
				(width 0.1)
				(type default)
			)
			(layer "F.Fab")
		)
		(fp_line
			(start 0.12065 -0.3048)
			(end 0.67945 -0.3048)
			(stroke
				(width 0.1)
				(type default)
			)
			(layer "F.Fab")
		)
		(fp_line
			(start 0.120396 0.3048)
			(end 0.120396 0.2794)
			(stroke
				(width 0.1)
				(type default)
			)
			(layer "F.Fab")
		)
		(fp_line
			(start 0.120396 0.2794)
			(end -0.12065 0.2794)
			(stroke
				(width 0.1)
				(type default)
			)
			(layer "F.Fab")
		)
		(fp_line
			(start -0.12065 0.3048)
			(end -0.67945 0.3048)
			(stroke
				(width 0.1)
				(type default)
			)
			(layer "F.Fab")
		)
		(fp_line
			(start -0.12065 0.2794)
			(end -0.12065 0.3048)
			(stroke
				(width 0.1)
				(type default)
			)
			(layer "F.Fab")
		)
		(fp_line
			(start -0.12065 -0.2794)
			(end 0.12065 -0.2794)
			(stroke
				(width 0.1)
				(type default)
			)
			(layer "F.Fab")
		)
		(fp_line
			(start -0.12065 -0.305054)
			(end -0.12065 -0.2794)
			(stroke
				(width 0.1)
				(type default)
			)
			(layer "F.Fab")
		)
		(fp_line
			(start -0.67945 0.3048)
			(end -0.67945 -0.305054)
			(stroke
				(width 0.1)
				(type default)
			)
			(layer "F.Fab")
		)
		(fp_line
			(start -0.67945 -0.305054)
			(end -0.12065 -0.305054)
			(stroke
				(width 0.1)
				(type default)
			)
			(layer "F.Fab")
		)
		(pad "1" smd circle
			(at -0.40005 0 180)
			(size 0 0)
			(layers "F.Cu" "F.Mask" "F.Paste")
			(net "FM_9ZXL045_1_OE_N")
		)
		(pad "2" smd circle
			(at 0.40005 0 180)
			(size 0 0)
			(layers "F.Cu" "F.Mask" "F.Paste")
			(net "CLK_GPU_1_OE_N")
		)
	)
)
